0.00800 T01
0.01000 T02
0.01200 T03
0.01417 T04
0.01456 T05
0.01600 T06
0.02244 T07
0.02800 T08
0.03200 T09
0.03400 T010
0.03500 T011
0.04000 T012
0.04800 T013
0.08600 T014
0.08700 T015
0.09400 T016
0.09700 T017
0.11900 T018
0.13000 T019
0.13400 T020
0.13800 T021
0.15800 T022
0.16800 T023
